(kicad_pcb
	(version 20260206)
	(generator "pcbnew")
	(generator_version "10.0")
	(general
		(thickness 1.6)
		(legacy_teardrops no)
	)
	(paper "A4")
	(title_block
		(title "04192023_DAF0TMB3IC0_F0TG_MB_C_brd_V02_OCP.brd")
		(comment 1 "Grand Teton / footprints 4058-4064 of 8354")
	)
	(layers
		(0 "F.Cu" signal "TOP")
		(4 "In1.Cu" signal "GND")
		(6 "In2.Cu" signal "IN1")
		(8 "In3.Cu" signal "GND1")
		(10 "In4.Cu" signal "IN2")
		(12 "In5.Cu" signal "GND2")
		(14 "In6.Cu" signal "IN3")
		(16 "In7.Cu" signal "GND3")
		(18 "In8.Cu" signal "VCC")
		(20 "In9.Cu" signal "VCC1")
		(22 "In10.Cu" signal "GND4")
		(24 "In11.Cu" signal "IN4")
		(26 "In12.Cu" signal "GND5")
		(28 "In13.Cu" signal "IN5")
		(30 "In14.Cu" signal "GND6")
		(32 "In15.Cu" signal "IN6")
		(34 "In16.Cu" signal "GND7")
		(2 "B.Cu" signal "BOTTOM")
		(9 "F.Adhes" user "F.Adhesive")
		(11 "B.Adhes" user "B.Adhesive")
		(13 "F.Paste" user "Package Geometry/Pastemask Top")
		(15 "B.Paste" user "Package Geometry/Pastemask Bottom")
		(5 "F.SilkS" user "Ref Des/Silkscreen Top")
		(7 "B.SilkS" user "Ref Des/Silkscreen Bottom")
		(1 "F.Mask" user "Board Geometry/Soldermask Top")
		(3 "B.Mask" user "Board Geometry/Soldermask Bottom")
		(17 "Dwgs.User" user "User.Drawings")
		(19 "Cmts.User" user "User.Comments")
		(21 "Eco1.User" user "User.Eco1")
		(23 "Eco2.User" user "User.Eco2")
		(25 "Edge.Cuts" user "Board Geometry/Outline")
		(27 "Margin" user)
		(31 "F.CrtYd" user "Package Geometry/Place Bound Top")
		(29 "B.CrtYd" user "Package Geometry/Place Bound Bottom")
		(35 "F.Fab" user "Ref Des/Assembly Top")
		(33 "B.Fab" user "Ref Des/Assembly Bottom")
	)
	(footprint ""
		(layer "F.Cu")
		(at 165.2016 -437.423052)
		(property "Reference" "R3463"
			(at 0 0 0)
			(layer "F.SilkS")
			(hide yes)
			(effects
				(font
					(size 1.27 1.27)
				)
			)
		)
		(property "Value" ""
			(at 0 0 0)
			(layer "F.Fab")
			(effects
				(font
					(size 1.27 1.27)
				)
			)
		)
		(duplicate_pad_numbers_are_jumpers no)
		(fp_line
			(start -0.7874 -0.4064)
			(end 0.7874 -0.4064)
			(stroke
				(width 0.1524)
				(type default)
			)
			(layer "F.SilkS")
		)
		(fp_line
			(start -0.7874 0.4064)
			(end -0.7874 -0.4064)
			(stroke
				(width 0.1524)
				(type default)
			)
			(layer "F.SilkS")
		)
		(fp_line
			(start 0.7874 -0.4064)
			(end 0.7874 0.4064)
			(stroke
				(width 0.1524)
				(type default)
			)
			(layer "F.SilkS")
		)
		(fp_line
			(start 0.7874 0.4064)
			(end -0.7874 0.4064)
			(stroke
				(width 0.1524)
				(type default)
			)
			(layer "F.SilkS")
		)
		(fp_line
			(start -0.67945 -0.305054)
			(end -0.12065 -0.305054)
			(stroke
				(width 0.1)
				(type default)
			)
			(layer "F.Fab")
		)
		(fp_line
			(start -0.67945 0.3048)
			(end -0.67945 -0.305054)
			(stroke
				(width 0.1)
				(type default)
			)
			(layer "F.Fab")
		)
		(fp_line
			(start -0.12065 -0.305054)
			(end -0.12065 -0.2794)
			(stroke
				(width 0.1)
				(type default)
			)
			(layer "F.Fab")
		)
		(fp_line
			(start -0.12065 -0.2794)
			(end 0.12065 -0.2794)
			(stroke
				(width 0.1)
				(type default)
			)
			(layer "F.Fab")
		)
		(fp_line
			(start -0.12065 0.2794)
			(end -0.12065 0.3048)
			(stroke
				(width 0.1)
				(type default)
			)
			(layer "F.Fab")
		)
		(fp_line
			(start -0.12065 0.3048)
			(end -0.67945 0.3048)
			(stroke
				(width 0.1)
				(type default)
			)
			(layer "F.Fab")
		)
		(fp_line
			(start 0.120396 0.2794)
			(end -0.12065 0.2794)
			(stroke
				(width 0.1)
				(type default)
			)
			(layer "F.Fab")
		)
		(fp_line
			(start 0.120396 0.3048)
			(end 0.120396 0.2794)
			(stroke
				(width 0.1)
				(type default)
			)
			(layer "F.Fab")
		)
		(fp_line
			(start 0.12065 -0.3048)
			(end 0.67945 -0.3048)
			(stroke
				(width 0.1)
				(type default)
			)
			(layer "F.Fab")
		)
		(fp_line
			(start 0.12065 -0.2794)
			(end 0.12065 -0.3048)
			(stroke
				(width 0.1)
				(type default)
			)
			(layer "F.Fab")
		)
		(fp_line
			(start 0.67945 -0.3048)
			(end 0.67945 0.3048)
			(stroke
				(width 0.1)
				(type default)
			)
			(layer "F.Fab")
		)
		(fp_line
			(start 0.67945 0.3048)
			(end 0.120396 0.3048)
			(stroke
				(width 0.1)
				(type default)
			)
			(layer "F.Fab")
		)
		(pad "1" smd circle
			(at -0.40005 0)
			(size 0 0)
			(layers "F.Cu" "F.Mask" "F.Paste")
			(net "GPU_BASE_HMC_READY")
		)
		(pad "2" smd circle
			(at 0.40005 0)
			(size 0 0)
			(layers "F.Cu" "F.Mask" "F.Paste")
			(net "GND")
		)
	)
	(footprint ""
		(layer "F.Cu")
		(at 9.238488 -135.32993 90)
		(property "Reference" "R4501"
			(at 0 0 90)
			(layer "F.SilkS")
			(hide yes)
			(effects
				(font
					(size 1.27 1.27)
				)
			)
		)
		(property "Value" ""
			(at 0 0 90)
			(layer "F.Fab")
			(effects
				(font
					(size 1.27 1.27)
				)
			)
		)
		(duplicate_pad_numbers_are_jumpers no)
		(fp_line
			(start 0.7874 -0.4064)
			(end 0.7874 0.4064)
			(stroke
				(width 0.1524)
				(type default)
			)
			(layer "F.SilkS")
		)
		(fp_line
			(start -0.7874 -0.4064)
			(end 0.7874 -0.4064)
			(stroke
				(width 0.1524)
				(type default)
			)
			(layer "F.SilkS")
		)
		(fp_line
			(start 0.7874 0.4064)
			(end -0.7874 0.4064)
			(stroke
				(width 0.1524)
				(type default)
			)
			(layer "F.SilkS")
		)
		(fp_line
			(start -0.7874 0.4064)
			(end -0.7874 -0.4064)
			(stroke
				(width 0.1524)
				(type default)
			)
			(layer "F.SilkS")
		)
		(fp_line
			(start -0.12065 -0.305054)
			(end -0.12065 -0.2794)
			(stroke
				(width 0.1)
				(type default)
			)
			(layer "F.Fab")
		)
		(fp_line
			(start -0.67945 -0.305054)
			(end -0.12065 -0.305054)
			(stroke
				(width 0.1)
				(type default)
			)
			(layer "F.Fab")
		)
		(fp_line
			(start 0.67945 -0.3048)
			(end 0.67945 0.3048)
			(stroke
				(width 0.1)
				(type default)
			)
			(layer "F.Fab")
		)
		(fp_line
			(start 0.12065 -0.3048)
			(end 0.67945 -0.3048)
			(stroke
				(width 0.1)
				(type default)
			)
			(layer "F.Fab")
		)
		(fp_line
			(start 0.12065 -0.2794)
			(end 0.12065 -0.3048)
			(stroke
				(width 0.1)
				(type default)
			)
			(layer "F.Fab")
		)
		(fp_line
			(start -0.12065 -0.2794)
			(end 0.12065 -0.2794)
			(stroke
				(width 0.1)
				(type default)
			)
			(layer "F.Fab")
		)
		(fp_line
			(start 0.120396 0.2794)
			(end -0.12065 0.2794)
			(stroke
				(width 0.1)
				(type default)
			)
			(layer "F.Fab")
		)
		(fp_line
			(start -0.12065 0.2794)
			(end -0.12065 0.3048)
			(stroke
				(width 0.1)
				(type default)
			)
			(layer "F.Fab")
		)
		(fp_line
			(start 0.67945 0.3048)
			(end 0.120396 0.3048)
			(stroke
				(width 0.1)
				(type default)
			)
			(layer "F.Fab")
		)
		(fp_line
			(start 0.120396 0.3048)
			(end 0.120396 0.2794)
			(stroke
				(width 0.1)
				(type default)
			)
			(layer "F.Fab")
		)
		(fp_line
			(start -0.12065 0.3048)
			(end -0.67945 0.3048)
			(stroke
				(width 0.1)
				(type default)
			)
			(layer "F.Fab")
		)
		(fp_line
			(start -0.67945 0.3048)
			(end -0.67945 -0.305054)
			(stroke
				(width 0.1)
				(type default)
			)
			(layer "F.Fab")
		)
		(pad "1" smd circle
			(at -0.40005 0 90)
			(size 0 0)
			(layers "F.Cu" "F.Mask" "F.Paste")
			(net "CLK_GEN2_XTAL_IN_R")
		)
		(pad "2" smd circle
			(at 0.40005 0 90)
			(size 0 0)
			(layers "F.Cu" "F.Mask" "F.Paste")
			(net "CLK_GEN2_XTAL_IN")
		)
	)
	(footprint ""
		(layer "F.Cu")
		(at 261.468616 -72.976994 180)
		(property "Reference" "R2125"
			(at 0 0 180)
			(layer "F.SilkS")
			(hide yes)
			(effects
				(font
					(size 1.27 1.27)
				)
			)
		)
		(property "Value" ""
			(at 0 0 180)
			(layer "F.Fab")
			(effects
				(font
					(size 1.27 1.27)
				)
			)
		)
		(duplicate_pad_numbers_are_jumpers no)
		(fp_line
			(start 0.7874 0.4064)
			(end -0.7874 0.4064)
			(stroke
				(width 0.1524)
				(type default)
			)
			(layer "F.SilkS")
		)
		(fp_line
			(start 0.7874 -0.4064)
			(end 0.7874 0.4064)
			(stroke
				(width 0.1524)
				(type default)
			)
			(layer "F.SilkS")
		)
		(fp_line
			(start -0.7874 0.4064)
			(end -0.7874 -0.4064)
			(stroke
				(width 0.1524)
				(type default)
			)
			(layer "F.SilkS")
		)
		(fp_line
			(start -0.7874 -0.4064)
			(end 0.7874 -0.4064)
			(stroke
				(width 0.1524)
				(type default)
			)
			(layer "F.SilkS")
		)
		(fp_line
			(start 0.67945 0.3048)
			(end 0.120396 0.3048)
			(stroke
				(width 0.1)
				(type default)
			)
			(layer "F.Fab")
		)
		(fp_line
			(start 0.67945 -0.3048)
			(end 0.67945 0.3048)
			(stroke
				(width 0.1)
				(type default)
			)
			(layer "F.Fab")
		)
		(fp_line
			(start 0.12065 -0.2794)
			(end 0.12065 -0.3048)
			(stroke
				(width 0.1)
				(type default)
			)
			(layer "F.Fab")
		)
		(fp_line
			(start 0.12065 -0.3048)
			(end 0.67945 -0.3048)
			(stroke
				(width 0.1)
				(type default)
			)
			(layer "F.Fab")
		)
		(fp_line
			(start 0.120396 0.3048)
			(end 0.120396 0.2794)
			(stroke
				(width 0.1)
				(type default)
			)
			(layer "F.Fab")
		)
		(fp_line
			(start 0.120396 0.2794)
			(end -0.12065 0.2794)
			(stroke
				(width 0.1)
				(type default)
			)
			(layer "F.Fab")
		)
		(fp_line
			(start -0.12065 0.3048)
			(end -0.67945 0.3048)
			(stroke
				(width 0.1)
				(type default)
			)
			(layer "F.Fab")
		)
		(fp_line
			(start -0.12065 0.2794)
			(end -0.12065 0.3048)
			(stroke
				(width 0.1)
				(type default)
			)
			(layer "F.Fab")
		)
		(fp_line
			(start -0.12065 -0.2794)
			(end 0.12065 -0.2794)
			(stroke
				(width 0.1)
				(type default)
			)
			(layer "F.Fab")
		)
		(fp_line
			(start -0.12065 -0.305054)
			(end -0.12065 -0.2794)
			(stroke
				(width 0.1)
				(type default)
			)
			(layer "F.Fab")
		)
		(fp_line
			(start -0.67945 0.3048)
			(end -0.67945 -0.305054)
			(stroke
				(width 0.1)
				(type default)
			)
			(layer "F.Fab")
		)
		(fp_line
			(start -0.67945 -0.305054)
			(end -0.12065 -0.305054)
			(stroke
				(width 0.1)
				(type default)
			)
			(layer "F.Fab")
		)
		(pad "1" smd circle
			(at -0.40005 0 180)
			(size 0 0)
			(layers "F.Cu" "F.Mask" "F.Paste")
			(net "P3V3_AUX")
		)
		(pad "2" smd circle
			(at 0.40005 0 180)
			(size 0 0)
			(layers "F.Cu" "F.Mask" "F.Paste")
			(net "SMB_PCIE_E1S_ISO_EN")
		)
	)
	(footprint ""
		(layer "F.Cu")
		(at 106.675936 -127.768096 -90)
		(property "Reference" "R1440"
			(at 0 0 270)
			(layer "F.SilkS")
			(hide yes)
			(effects
				(font
					(size 1.27 1.27)
				)
			)
		)
		(property "Value" ""
			(at 0 0 270)
			(layer "F.Fab")
			(effects
				(font
					(size 1.27 1.27)
				)
			)
		)
		(duplicate_pad_numbers_are_jumpers no)
		(fp_line
			(start -0.7874 0.4064)
			(end -0.7874 -0.4064)
			(stroke
				(width 0.1524)
				(type default)
			)
			(layer "F.SilkS")
		)
		(fp_line
			(start 0.7874 0.4064)
			(end -0.7874 0.4064)
			(stroke
				(width 0.1524)
				(type default)
			)
			(layer "F.SilkS")
		)
		(fp_line
			(start -0.7874 -0.4064)
			(end 0.7874 -0.4064)
			(stroke
				(width 0.1524)
				(type default)
			)
			(layer "F.SilkS")
		)
		(fp_line
			(start 0.7874 -0.4064)
			(end 0.7874 0.4064)
			(stroke
				(width 0.1524)
				(type default)
			)
			(layer "F.SilkS")
		)
		(fp_line
			(start -0.67945 0.3048)
			(end -0.67945 -0.305054)
			(stroke
				(width 0.1)
				(type default)
			)
			(layer "F.Fab")
		)
		(fp_line
			(start -0.12065 0.3048)
			(end -0.67945 0.3048)
			(stroke
				(width 0.1)
				(type default)
			)
			(layer "F.Fab")
		)
		(fp_line
			(start 0.120396 0.3048)
			(end 0.120396 0.2794)
			(stroke
				(width 0.1)
				(type default)
			)
			(layer "F.Fab")
		)
		(fp_line
			(start 0.67945 0.3048)
			(end 0.120396 0.3048)
			(stroke
				(width 0.1)
				(type default)
			)
			(layer "F.Fab")
		)
		(fp_line
			(start -0.12065 0.2794)
			(end -0.12065 0.3048)
			(stroke
				(width 0.1)
				(type default)
			)
			(layer "F.Fab")
		)
		(fp_line
			(start 0.120396 0.2794)
			(end -0.12065 0.2794)
			(stroke
				(width 0.1)
				(type default)
			)
			(layer "F.Fab")
		)
		(fp_line
			(start -0.12065 -0.2794)
			(end 0.12065 -0.2794)
			(stroke
				(width 0.1)
				(type default)
			)
			(layer "F.Fab")
		)
		(fp_line
			(start 0.12065 -0.2794)
			(end 0.12065 -0.3048)
			(stroke
				(width 0.1)
				(type default)
			)
			(layer "F.Fab")
		)
		(fp_line
			(start 0.12065 -0.3048)
			(end 0.67945 -0.3048)
			(stroke
				(width 0.1)
				(type default)
			)
			(layer "F.Fab")
		)
		(fp_line
			(start 0.67945 -0.3048)
			(end 0.67945 0.3048)
			(stroke
				(width 0.1)
				(type default)
			)
			(layer "F.Fab")
		)
		(fp_line
			(start -0.67945 -0.305054)
			(end -0.12065 -0.305054)
			(stroke
				(width 0.1)
				(type default)
			)
			(layer "F.Fab")
		)
		(fp_line
			(start -0.12065 -0.305054)
			(end -0.12065 -0.2794)
			(stroke
				(width 0.1)
				(type default)
			)
			(layer "F.Fab")
		)
		(pad "1" smd circle
			(at -0.40005 0 270)
			(size 0 0)
			(layers "F.Cu" "F.Mask" "F.Paste")
			(net "P12V_MEM_CPU1")
		)
		(pad "2" smd circle
			(at 0.40005 0 270)
			(size 0 0)
			(layers "F.Cu" "F.Mask" "F.Paste")
			(net "PWRGD_P12V_MEM_CPU1_EN")
		)
	)
	(footprint ""
		(layer "F.Cu")
		(at 249.916696 -44.572682 180)
		(property "Reference" "PR3961"
			(at 0 0 180)
			(layer "F.SilkS")
			(hide yes)
			(effects
				(font
					(size 1.27 1.27)
				)
			)
		)
		(property "Value" ""
			(at 0 0 180)
			(layer "F.Fab")
			(effects
				(font
					(size 1.27 1.27)
				)
			)
		)
		(duplicate_pad_numbers_are_jumpers no)
		(fp_line
			(start 0.7874 0.4064)
			(end -0.7874 0.4064)
			(stroke
				(width 0.1524)
				(type default)
			)
			(layer "F.SilkS")
		)
		(fp_line
			(start 0.7874 -0.4064)
			(end 0.7874 0.4064)
			(stroke
				(width 0.1524)
				(type default)
			)
			(layer "F.SilkS")
		)
		(fp_line
			(start -0.7874 0.4064)
			(end -0.7874 -0.4064)
			(stroke
				(width 0.1524)
				(type default)
			)
			(layer "F.SilkS")
		)
		(fp_line
			(start -0.7874 -0.4064)
			(end 0.7874 -0.4064)
			(stroke
				(width 0.1524)
				(type default)
			)
			(layer "F.SilkS")
		)
		(fp_line
			(start 0.67945 0.3048)
			(end 0.120396 0.3048)
			(stroke
				(width 0.1)
				(type default)
			)
			(layer "F.Fab")
		)
		(fp_line
			(start 0.67945 -0.3048)
			(end 0.67945 0.3048)
			(stroke
				(width 0.1)
				(type default)
			)
			(layer "F.Fab")
		)
		(fp_line
			(start 0.12065 -0.2794)
			(end 0.12065 -0.3048)
			(stroke
				(width 0.1)
				(type default)
			)
			(layer "F.Fab")
		)
		(fp_line
			(start 0.12065 -0.3048)
			(end 0.67945 -0.3048)
			(stroke
				(width 0.1)
				(type default)
			)
			(layer "F.Fab")
		)
		(fp_line
			(start 0.120396 0.3048)
			(end 0.120396 0.2794)
			(stroke
				(width 0.1)
				(type default)
			)
			(layer "F.Fab")
		)
		(fp_line
			(start 0.120396 0.2794)
			(end -0.12065 0.2794)
			(stroke
				(width 0.1)
				(type default)
			)
			(layer "F.Fab")
		)
		(fp_line
			(start -0.12065 0.3048)
			(end -0.67945 0.3048)
			(stroke
				(width 0.1)
				(type default)
			)
			(layer "F.Fab")
		)
		(fp_line
			(start -0.12065 0.2794)
			(end -0.12065 0.3048)
			(stroke
				(width 0.1)
				(type default)
			)
			(layer "F.Fab")
		)
		(fp_line
			(start -0.12065 -0.2794)
			(end 0.12065 -0.2794)
			(stroke
				(width 0.1)
				(type default)
			)
			(layer "F.Fab")
		)
		(fp_line
			(start -0.12065 -0.305054)
			(end -0.12065 -0.2794)
			(stroke
				(width 0.1)
				(type default)
			)
			(layer "F.Fab")
		)
		(fp_line
			(start -0.67945 0.3048)
			(end -0.67945 -0.305054)
			(stroke
				(width 0.1)
				(type default)
			)
			(layer "F.Fab")
		)
		(fp_line
			(start -0.67945 -0.305054)
			(end -0.12065 -0.305054)
			(stroke
				(width 0.1)
				(type default)
			)
			(layer "F.Fab")
		)
		(pad "1" smd circle
			(at -0.40005 0 180)
			(size 0 0)
			(layers "F.Cu" "F.Mask" "F.Paste")
			(net "P12V_E1S_UV_0")
		)
		(pad "2" smd circle
			(at 0.40005 0 180)
			(size 0 0)
			(layers "F.Cu" "F.Mask" "F.Paste")
			(net "P12V_E1S_OV_0")
		)
	)
	(footprint ""
		(layer "F.Cu")
		(at 420.74084 -378.95403 -90)
		(property "Reference" "C845"
			(at 0 0 270)
			(layer "F.SilkS")
			(hide yes)
			(effects
				(font
					(size 1.27 1.27)
				)
			)
		)
		(property "Value" ""
			(at 0 0 270)
			(layer "F.Fab")
			(effects
				(font
					(size 1.27 1.27)
				)
			)
		)
		(duplicate_pad_numbers_are_jumpers no)
		(fp_line
			(start -0.299974 0.150114)
			(end -0.299974 -0.150114)
			(stroke
				(width 0.1)
				(type default)
			)
			(layer "F.Fab")
		)
		(fp_line
			(start 0.299974 0.150114)
			(end -0.299974 0.150114)
			(stroke
				(width 0.1)
				(type default)
			)
			(layer "F.Fab")
		)
		(fp_line
			(start -0.299974 -0.150114)
			(end 0.299974 -0.150114)
			(stroke
				(width 0.1)
				(type default)
			)
			(layer "F.Fab")
		)
		(fp_line
			(start 0.299974 -0.150114)
			(end 0.299974 0.150114)
			(stroke
				(width 0.1)
				(type default)
			)
			(layer "F.Fab")
		)
		(pad "1" smd rect
			(at -0.2667 0 270)
			(size 0.3048 0.381)
			(layers "F.Cu" "F.Mask" "F.Paste")
			(net "P5E_CPU0_P2_TX_C_DP<12>")
		)
		(pad "2" smd rect
			(at 0.2667 0 270)
			(size 0.3048 0.381)
			(layers "F.Cu" "F.Mask" "F.Paste")
			(net "P5E_CPU0_P2_TX_DP<12>")
		)
	)
	(footprint ""
		(layer "F.Cu")
		(at 100.03536 -336.935064 180)
		(property "Reference" "PC208"
			(at 0 0 180)
			(layer "F.SilkS")
			(hide yes)
			(effects
				(font
					(size 1.27 1.27)
				)
			)
		)
		(property "Value" ""
			(at 0 0 180)
			(layer "F.Fab")
			(effects
				(font
					(size 1.27 1.27)
				)
			)
		)
		(duplicate_pad_numbers_are_jumpers no)
		(fp_line
			(start 0.7874 0.4064)
			(end -0.7874 0.4064)
			(stroke
				(width 0.1524)
				(type default)
			)
			(layer "F.SilkS")
		)
		(fp_line
			(start 0.7874 -0.4064)
			(end 0.7874 0.4064)
			(stroke
				(width 0.1524)
				(type default)
			)
			(layer "F.SilkS")
		)
		(fp_line
			(start -0.7874 0.4064)
			(end -0.7874 -0.4064)
			(stroke
				(width 0.1524)
				(type default)
			)
			(layer "F.SilkS")
		)
		(fp_line
			(start -0.7874 -0.4064)
			(end 0.7874 -0.4064)
			(stroke
				(width 0.1524)
				(type default)
			)
			(layer "F.SilkS")
		)
		(fp_line
			(start 0.67945 0.3048)
			(end 0.120396 0.3048)
			(stroke
				(width 0.1)
				(type default)
			)
			(layer "F.Fab")
		)
		(fp_line
			(start 0.67945 -0.3048)
			(end 0.67945 0.3048)
			(stroke
				(width 0.1)
				(type default)
			)
			(layer "F.Fab")
		)
		(fp_line
			(start 0.12065 -0.2794)
			(end 0.12065 -0.3048)
			(stroke
				(width 0.1)
				(type default)
			)
			(layer "F.Fab")
		)
		(fp_line
			(start 0.12065 -0.3048)
			(end 0.67945 -0.3048)
			(stroke
				(width 0.1)
				(type default)
			)
			(layer "F.Fab")
		)
		(fp_line
			(start 0.120396 0.3048)
			(end 0.120396 0.2794)
			(stroke
				(width 0.1)
				(type default)
			)
			(layer "F.Fab")
		)
		(fp_line
			(start 0.120396 0.2794)
			(end -0.12065 0.2794)
			(stroke
				(width 0.1)
				(type default)
			)
			(layer "F.Fab")
		)
		(fp_line
			(start -0.12065 0.3048)
			(end -0.67945 0.3048)
			(stroke
				(width 0.1)
				(type default)
			)
			(layer "F.Fab")
		)
		(fp_line
			(start -0.12065 0.2794)
			(end -0.12065 0.3048)
			(stroke
				(width 0.1)
				(type default)
			)
			(layer "F.Fab")
		)
		(fp_line
			(start -0.12065 -0.2794)
			(end 0.12065 -0.2794)
			(stroke
				(width 0.1)
				(type default)
			)
			(layer "F.Fab")
		)
		(fp_line
			(start -0.12065 -0.305054)
			(end -0.12065 -0.2794)
			(stroke
				(width 0.1)
				(type default)
			)
			(layer "F.Fab")
		)
		(fp_line
			(start -0.67945 0.3048)
			(end -0.67945 -0.305054)
			(stroke
				(width 0.1)
				(type default)
			)
			(layer "F.Fab")
		)
		(fp_line
			(start -0.67945 -0.305054)
			(end -0.12065 -0.305054)
			(stroke
				(width 0.1)
				(type default)
			)
			(layer "F.Fab")
		)
		(pad "1" smd circle
			(at -0.40005 0 180)
			(size 0 0)
			(layers "F.Cu" "F.Mask" "F.Paste")
			(net "SW_PVDDCR_CPU1_P1_SW6")
		)
		(pad "2" smd circle
			(at 0.40005 0 180)
			(size 0 0)
			(layers "F.Cu" "F.Mask" "F.Paste")
			(net "SW_PVDDCR_CPU1_P1_SW6_RC")
		)
	)
)
